(kicad_pcb
	(version 20260206)
	(generator "pcbnew")
	(generator_version "10.0")
	(general
		(thickness 1.6)
		(legacy_teardrops no)
	)
	(paper "A4")
	(title_block
		(title "fcb — Lightning_FCB_BRD.brd")
		(comment 1 "Lightning (Wiwynn / Facebook NVMe JBOF) / footprints 105-112 of 495")
	)
	(layers
		(0 "F.Cu" signal "TOP")
		(4 "In1.Cu" signal "L2GND")
		(6 "In2.Cu" signal "L3VCC")
		(2 "B.Cu" signal "BOTTOM")
		(9 "F.Adhes" user "F.Adhesive")
		(11 "B.Adhes" user "B.Adhesive")
		(13 "F.Paste" user "Package Geometry/Pastemask Top")
		(15 "B.Paste" user "Package Geometry/Pastemask Bottom")
		(5 "F.SilkS" user "Ref Des/Silkscreen Top")
		(7 "B.SilkS" user "Ref Des/Silkscreen Bottom")
		(1 "F.Mask" user "Board Geometry/Soldermask Top")
		(3 "B.Mask" user "Board Geometry/Soldermask Bottom")
		(17 "Dwgs.User" user "User.Drawings")
		(19 "Cmts.User" user "User.Comments")
		(21 "Eco1.User" user "User.Eco1")
		(23 "Eco2.User" user "User.Eco2")
		(25 "Edge.Cuts" user "Board Geometry/Outline")
		(27 "Margin" user)
		(31 "F.CrtYd" user "Package Geometry/Place Bound Top")
		(29 "B.CrtYd" user "Package Geometry/Place Bound Bottom")
		(35 "F.Fab" user "Ref Des/Assembly Top")
		(33 "B.Fab" user "Ref Des/Assembly Bottom")
	)
	(footprint ""
		(layer "F.Cu")
		(at 29.852366 -242.327176)
		(property "Reference" "R43"
			(at 0 0 0)
			(layer "F.SilkS")
			(hide yes)
			(effects
				(font
					(size 1.27 1.27)
				)
			)
		)
		(property "Value" "4K7R2J-2-GP"
			(at 0.064008 -3.993896 0)
			(unlocked yes)
			(layer "F.Fab")
			(hide yes)
			(effects
				(font
					(size 1.016 1.016)
					(thickness 0.1524)
				)
			)
		)
		(property "Device Type" "R402H16"
			(at 0.064008 -5.517896 0)
			(unlocked yes)
			(layer "F.Fab")
			(hide yes)
			(effects
				(font
					(size 1.016 1.016)
					(thickness 0.1524)
				)
			)
		)
		(duplicate_pad_numbers_are_jumpers no)
		(fp_line
			(start -0.508 -0.9398)
			(end -0.508 0.9398)
			(stroke
				(width 0.1524)
				(type default)
			)
			(layer "F.SilkS")
		)
		(fp_line
			(start 0.508 -0.9398)
			(end -0.508 -0.9398)
			(stroke
				(width 0.1524)
				(type default)
			)
			(layer "F.SilkS")
		)
		(fp_rect
			(start -0.508 0.9398)
			(end 0.508 -0.9398)
			(stroke
				(width 0)
				(type default)
			)
			(fill no)
			(layer "F.CrtYd")
		)
		(fp_rect
			(start -0.508 0.9398)
			(end 0.508 -0.9398)
			(stroke
				(width 0)
				(type default)
			)
			(fill no)
			(layer "F.Fab")
		)
		(pad "1" smd custom
			(at 0 -0.4445)
			(size 0.1397 0.1397)
			(layers "F.Cu" "F.Mask" "F.Paste")
			(net "FCB_EEPROM_A1")
			(options
				(clearance outline)
				(anchor circle)
			)
			(primitives
				(gr_poly
					(pts
						(arc
							(start -0.1778 -0.2794)
							(mid -0.249642 -0.249642)
							(end -0.2794 -0.1778)
						)
						(arc
							(start -0.2794 0.1778)
							(mid -0.249642 0.249642)
							(end -0.1778 0.2794)
						)
						(arc
							(start 0.1778 0.2794)
							(mid 0.249642 0.249642)
							(end 0.2794 0.1778)
						)
						(arc
							(start 0.2794 -0.1778)
							(mid 0.249642 -0.249642)
							(end 0.1778 -0.2794)
						)
					)
					(width 0)
					(fill yes)
				)
			)
		)
		(pad "2" smd custom
			(at 0 0.4445)
			(size 0.1397 0.1397)
			(layers "F.Cu" "F.Mask" "F.Paste")
			(net "GND")
			(options
				(clearance outline)
				(anchor circle)
			)
			(primitives
				(gr_poly
					(pts
						(arc
							(start -0.1778 -0.2794)
							(mid -0.249642 -0.249642)
							(end -0.2794 -0.1778)
						)
						(arc
							(start -0.2794 0.1778)
							(mid -0.249642 0.249642)
							(end -0.1778 0.2794)
						)
						(arc
							(start 0.1778 0.2794)
							(mid 0.249642 0.249642)
							(end 0.2794 0.1778)
						)
						(arc
							(start 0.2794 -0.1778)
							(mid 0.249642 -0.249642)
							(end 0.1778 -0.2794)
						)
					)
					(width 0)
					(fill yes)
				)
			)
		)
	)
	(footprint ""
		(layer "F.Cu")
		(at 37.973 -147.4216 180)
		(property "Reference" "PC94"
			(at 0 0 180)
			(layer "F.SilkS")
			(hide yes)
			(effects
				(font
					(size 1.27 1.27)
				)
			)
		)
		(property "Value" "SC220P50V2KX-3GP"
			(at 1.1811 -2.7051 180)
			(unlocked yes)
			(layer "F.Fab")
			(hide yes)
			(effects
				(font
					(size 1.016 1.016)
					(thickness 0.1524)
				)
			)
		)
		(property "Device Type" "C402H22"
			(at 1.1811 -4.2291 180)
			(unlocked yes)
			(layer "F.Fab")
			(hide yes)
			(effects
				(font
					(size 1.016 1.016)
					(thickness 0.1524)
				)
			)
		)
		(duplicate_pad_numbers_are_jumpers no)
		(fp_rect
			(start -0.4318 0.9525)
			(end 0.4318 -0.9525)
			(stroke
				(width 0)
				(type default)
			)
			(fill no)
			(layer "F.CrtYd")
		)
		(fp_rect
			(start -0.4318 0.9525)
			(end 0.4318 -0.9525)
			(stroke
				(width 0)
				(type default)
			)
			(fill no)
			(layer "F.Fab")
		)
		(pad "1" smd custom
			(at 0 -0.4445 180)
			(size 0.1524 0.1524)
			(layers "F.Cu" "F.Mask" "F.Paste")
			(net "P12VL_2490_VREF")
			(options
				(clearance outline)
				(anchor circle)
			)
			(primitives
				(gr_poly
					(pts
						(arc
							(start 0.3048 -0.2032)
							(mid 0.275042 -0.275042)
							(end 0.2032 -0.3048)
						)
						(arc
							(start -0.2032 -0.3048)
							(mid -0.275042 -0.275042)
							(end -0.3048 -0.2032)
						)
						(arc
							(start -0.3048 0.2032)
							(mid -0.275042 0.275042)
							(end -0.2032 0.3048)
						)
						(arc
							(start 0.2032 0.3048)
							(mid 0.275042 0.275042)
							(end 0.3048 0.2032)
						)
					)
					(width 0)
					(fill yes)
				)
			)
		)
		(pad "2" smd custom
			(at 0 0.4445 180)
			(size 0.1524 0.1524)
			(layers "F.Cu" "F.Mask" "F.Paste")
			(net "GND")
			(options
				(clearance outline)
				(anchor circle)
			)
			(primitives
				(gr_poly
					(pts
						(arc
							(start 0.3048 -0.2032)
							(mid 0.275042 -0.275042)
							(end 0.2032 -0.3048)
						)
						(arc
							(start -0.2032 -0.3048)
							(mid -0.275042 -0.275042)
							(end -0.3048 -0.2032)
						)
						(arc
							(start -0.3048 0.2032)
							(mid -0.275042 0.275042)
							(end -0.2032 0.3048)
						)
						(arc
							(start 0.2032 0.3048)
							(mid 0.275042 0.275042)
							(end 0.3048 0.2032)
						)
					)
					(width 0)
					(fill yes)
				)
			)
		)
	)
	(footprint ""
		(layer "F.Cu")
		(at 6.5786 -437.7436)
		(property "Reference" "R32"
			(at 0 0 0)
			(layer "F.SilkS")
			(hide yes)
			(effects
				(font
					(size 1.27 1.27)
				)
			)
		)
		(property "Value" "0R2J-2-GP"
			(at 0.064008 -3.993896 0)
			(unlocked yes)
			(layer "F.Fab")
			(hide yes)
			(effects
				(font
					(size 1.016 1.016)
					(thickness 0.1524)
				)
			)
		)
		(property "Device Type" "R402H16"
			(at 0.064008 -5.517896 0)
			(unlocked yes)
			(layer "F.Fab")
			(hide yes)
			(effects
				(font
					(size 1.016 1.016)
					(thickness 0.1524)
				)
			)
		)
		(duplicate_pad_numbers_are_jumpers no)
		(fp_line
			(start -0.508 -0.9398)
			(end -0.508 0.9398)
			(stroke
				(width 0.1524)
				(type default)
			)
			(layer "F.SilkS")
		)
		(fp_line
			(start 0.508 -0.9398)
			(end -0.508 -0.9398)
			(stroke
				(width 0.1524)
				(type default)
			)
			(layer "F.SilkS")
		)
		(fp_rect
			(start -0.508 0.9398)
			(end 0.508 -0.9398)
			(stroke
				(width 0)
				(type default)
			)
			(fill no)
			(layer "F.CrtYd")
		)
		(fp_rect
			(start -0.508 0.9398)
			(end 0.508 -0.9398)
			(stroke
				(width 0)
				(type default)
			)
			(fill no)
			(layer "F.Fab")
		)
		(pad "1" smd custom
			(at 0 -0.4445)
			(size 0.1397 0.1397)
			(layers "F.Cu" "F.Mask" "F.Paste")
			(net "LED_DR_LED0_K")
			(options
				(clearance outline)
				(anchor circle)
			)
			(primitives
				(gr_poly
					(pts
						(arc
							(start -0.1778 -0.2794)
							(mid -0.249642 -0.249642)
							(end -0.2794 -0.1778)
						)
						(arc
							(start -0.2794 0.1778)
							(mid -0.249642 0.249642)
							(end -0.1778 0.2794)
						)
						(arc
							(start 0.1778 0.2794)
							(mid 0.249642 0.249642)
							(end 0.2794 0.1778)
						)
						(arc
							(start 0.2794 -0.1778)
							(mid 0.249642 -0.249642)
							(end 0.1778 -0.2794)
						)
					)
					(width 0)
					(fill yes)
				)
			)
		)
		(pad "2" smd custom
			(at 0 0.4445)
			(size 0.1397 0.1397)
			(layers "F.Cu" "F.Mask" "F.Paste")
			(net "GND")
			(options
				(clearance outline)
				(anchor circle)
			)
			(primitives
				(gr_poly
					(pts
						(arc
							(start -0.1778 -0.2794)
							(mid -0.249642 -0.249642)
							(end -0.2794 -0.1778)
						)
						(arc
							(start -0.2794 0.1778)
							(mid -0.249642 0.249642)
							(end -0.1778 0.2794)
						)
						(arc
							(start 0.1778 0.2794)
							(mid 0.249642 0.249642)
							(end 0.2794 0.1778)
						)
						(arc
							(start 0.2794 -0.1778)
							(mid 0.249642 -0.249642)
							(end 0.1778 -0.2794)
						)
					)
					(width 0)
					(fill yes)
				)
			)
		)
	)
	(footprint ""
		(layer "F.Cu")
		(at 14.8844 -41.4782 90)
		(property "Reference" "R116"
			(at 0 0 90)
			(layer "F.SilkS")
			(hide yes)
			(effects
				(font
					(size 1.27 1.27)
				)
			)
		)
		(property "Value" "470R2F-GP"
			(at 0.064008 -3.993896 90)
			(unlocked yes)
			(layer "F.Fab")
			(hide yes)
			(effects
				(font
					(size 1.016 1.016)
					(thickness 0.1524)
				)
			)
		)
		(property "Device Type" "R402H16"
			(at 0.064008 -5.517896 90)
			(unlocked yes)
			(layer "F.Fab")
			(hide yes)
			(effects
				(font
					(size 1.016 1.016)
					(thickness 0.1524)
				)
			)
		)
		(duplicate_pad_numbers_are_jumpers no)
		(fp_line
			(start 0.508 -0.9398)
			(end -0.508 -0.9398)
			(stroke
				(width 0.1524)
				(type default)
			)
			(layer "F.SilkS")
		)
		(fp_line
			(start -0.508 -0.9398)
			(end -0.508 0.9398)
			(stroke
				(width 0.1524)
				(type default)
			)
			(layer "F.SilkS")
		)
		(fp_rect
			(start -0.508 0.9398)
			(end 0.508 -0.9398)
			(stroke
				(width 0)
				(type default)
			)
			(fill no)
			(layer "F.CrtYd")
		)
		(fp_rect
			(start -0.508 0.9398)
			(end 0.508 -0.9398)
			(stroke
				(width 0)
				(type default)
			)
			(fill no)
			(layer "F.Fab")
		)
		(pad "1" smd custom
			(at 0 -0.4445 90)
			(size 0.1397 0.1397)
			(layers "F.Cu" "F.Mask" "F.Paste")
			(net "SEB_PEER_1B_HB")
			(options
				(clearance outline)
				(anchor circle)
			)
			(primitives
				(gr_poly
					(pts
						(arc
							(start -0.1778 -0.2794)
							(mid -0.249642 -0.249642)
							(end -0.2794 -0.1778)
						)
						(arc
							(start -0.2794 0.1778)
							(mid -0.249642 0.249642)
							(end -0.1778 0.2794)
						)
						(arc
							(start 0.1778 0.2794)
							(mid 0.249642 0.249642)
							(end 0.2794 0.1778)
						)
						(arc
							(start 0.2794 -0.1778)
							(mid 0.249642 -0.249642)
							(end 0.1778 -0.2794)
						)
					)
					(width 0)
					(fill yes)
				)
			)
		)
		(pad "2" smd custom
			(at 0 0.4445 90)
			(size 0.1397 0.1397)
			(layers "F.Cu" "F.Mask" "F.Paste")
			(net "GND")
			(options
				(clearance outline)
				(anchor circle)
			)
			(primitives
				(gr_poly
					(pts
						(arc
							(start -0.1778 -0.2794)
							(mid -0.249642 -0.249642)
							(end -0.2794 -0.1778)
						)
						(arc
							(start -0.2794 0.1778)
							(mid -0.249642 0.249642)
							(end -0.1778 0.2794)
						)
						(arc
							(start 0.1778 0.2794)
							(mid 0.249642 0.249642)
							(end 0.2794 0.1778)
						)
						(arc
							(start 0.2794 -0.1778)
							(mid 0.249642 -0.249642)
							(end 0.1778 -0.2794)
						)
					)
					(width 0)
					(fill yes)
				)
			)
		)
	)
	(footprint ""
		(layer "F.Cu")
		(at 15.9258 -65.278)
		(property "Reference" "C57"
			(at 0 0 0)
			(layer "F.SilkS")
			(hide yes)
			(effects
				(font
					(size 1.27 1.27)
				)
			)
		)
		(property "Value" "SC220P50V3JN-GP"
			(at 0 -2.8194 0)
			(unlocked yes)
			(layer "F.Fab")
			(hide yes)
			(effects
				(font
					(size 1.016 1.016)
					(thickness 0.1524)
				)
			)
		)
		(property "Device Type" "C603H36"
			(at 0 -4.3434 0)
			(unlocked yes)
			(layer "F.Fab")
			(hide yes)
			(effects
				(font
					(size 1.016 1.016)
					(thickness 0.1524)
				)
			)
		)
		(duplicate_pad_numbers_are_jumpers no)
		(fp_line
			(start 0.508 0)
			(end -0.508 0)
			(stroke
				(width 0.2032)
				(type default)
			)
			(layer "F.SilkS")
		)
		(fp_rect
			(start -0.5842 1.3335)
			(end 0.5842 -1.3335)
			(stroke
				(width 0)
				(type default)
			)
			(fill no)
			(layer "F.CrtYd")
		)
		(fp_rect
			(start -0.5842 1.3335)
			(end 0.5842 -1.3335)
			(stroke
				(width 0)
				(type default)
			)
			(fill no)
			(layer "F.Fab")
		)
		(pad "1" smd custom
			(at 0 -0.762)
			(size 0.2159 0.2159)
			(layers "F.Cu" "F.Mask" "F.Paste")
			(net "I2C_C_SDA_CONN_R")
			(options
				(clearance outline)
				(anchor circle)
			)
			(primitives
				(gr_poly
					(pts
						(arc
							(start -0.3302 -0.4318)
							(mid -0.402042 -0.402042)
							(end -0.4318 -0.3302)
						)
						(arc
							(start -0.4318 0.3302)
							(mid -0.402042 0.402042)
							(end -0.3302 0.4318)
						)
						(arc
							(start 0.3302 0.4318)
							(mid 0.402042 0.402042)
							(end 0.4318 0.3302)
						)
						(arc
							(start 0.4318 -0.3302)
							(mid 0.402042 -0.402042)
							(end 0.3302 -0.4318)
						)
					)
					(width 0)
					(fill yes)
				)
			)
		)
		(pad "2" smd custom
			(at 0 0.762)
			(size 0.2159 0.2159)
			(layers "F.Cu" "F.Mask" "F.Paste")
			(net "GND")
			(options
				(clearance outline)
				(anchor circle)
			)
			(primitives
				(gr_poly
					(pts
						(arc
							(start -0.3302 -0.4318)
							(mid -0.402042 -0.402042)
							(end -0.4318 -0.3302)
						)
						(arc
							(start -0.4318 0.3302)
							(mid -0.402042 0.402042)
							(end -0.3302 0.4318)
						)
						(arc
							(start 0.3302 0.4318)
							(mid 0.402042 0.402042)
							(end 0.4318 0.3302)
						)
						(arc
							(start 0.4318 -0.3302)
							(mid 0.402042 -0.402042)
							(end 0.3302 -0.4318)
						)
					)
					(width 0)
					(fill yes)
				)
			)
		)
	)
	(footprint ""
		(layer "F.Cu")
		(at 22.479508 -286.917638)
		(property "Reference" "D10"
			(at 0 0 0)
			(layer "F.SilkS")
			(hide yes)
			(effects
				(font
					(size 1.27 1.27)
				)
			)
		)
		(property "Value" "BAS16H-GP"
			(at 0 -5.5372 0)
			(unlocked yes)
			(layer "F.Fab")
			(hide yes)
			(effects
				(font
					(size 1.016 1.016)
					(thickness 0.1524)
				)
			)
		)
		(property "Device Type" "SOD123AKH48"
			(at 0 -7.0612 0)
			(unlocked yes)
			(layer "F.Fab")
			(hide yes)
			(effects
				(font
					(size 1.016 1.016)
					(thickness 0.1524)
				)
			)
		)
		(duplicate_pad_numbers_are_jumpers no)
		(fp_line
			(start -1.016 -2.667)
			(end -1.016 2.667)
			(stroke
				(width 0.1524)
				(type default)
			)
			(layer "F.SilkS")
		)
		(fp_line
			(start -1.016 2.667)
			(end 1.016 2.667)
			(stroke
				(width 0.1524)
				(type default)
			)
			(layer "F.SilkS")
		)
		(fp_line
			(start 0.889 2.921)
			(end -0.889 2.921)
			(stroke
				(width 0.508)
				(type default)
			)
			(layer "F.SilkS")
		)
		(fp_line
			(start 1.016 -2.667)
			(end -1.016 -2.667)
			(stroke
				(width 0.1524)
				(type default)
			)
			(layer "F.SilkS")
		)
		(fp_line
			(start 1.016 2.667)
			(end 1.016 -2.667)
			(stroke
				(width 0.1524)
				(type default)
			)
			(layer "F.SilkS")
		)
		(fp_rect
			(start -1.143 3.175)
			(end 1.143 -2.794)
			(stroke
				(width 0)
				(type default)
			)
			(fill no)
			(layer "F.CrtYd")
		)
		(fp_poly
			(pts
				(xy -1.143 -2.794) (xy 1.143 -2.794) (xy 1.143 3.175) (xy -1.143 3.175)
			)
			(stroke
				(width 0)
				(type default)
			)
			(fill no)
			(layer "F.Fab")
		)
		(pad "A" smd rect
			(at 0 -1.6891)
			(size 0.889 1.397)
			(layers "F.Cu" "F.Mask" "F.Paste")
			(net "FAN_TACH4")
		)
		(pad "K" smd rect
			(at 0 1.6891)
			(size 0.889 1.397)
			(layers "F.Cu" "F.Mask" "F.Paste")
			(net "P12V")
		)
	)
	(footprint ""
		(layer "F.Cu")
		(at 17.9578 -150.114 -90)
		(property "Reference" "R72"
			(at 0 0 270)
			(layer "F.SilkS")
			(hide yes)
			(effects
				(font
					(size 1.27 1.27)
				)
			)
		)
		(property "Value" "27KR3F-GP"
			(at -0.0254 -2.5146 270)
			(unlocked yes)
			(layer "F.Fab")
			(hide yes)
			(effects
				(font
					(size 1.016 1.016)
					(thickness 0.1524)
				)
			)
		)
		(property "Device Type" "R603H22"
			(at -0.0254 -4.0386 270)
			(unlocked yes)
			(layer "F.Fab")
			(hide yes)
			(effects
				(font
					(size 1.016 1.016)
					(thickness 0.1524)
				)
			)
		)
		(duplicate_pad_numbers_are_jumpers no)
		(fp_line
			(start -0.4826 0)
			(end -0.2032 0)
			(stroke
				(width 0.2032)
				(type default)
			)
			(layer "F.SilkS")
		)
		(fp_line
			(start 0.2032 0)
			(end 0.4826 0)
			(stroke
				(width 0.2032)
				(type default)
			)
			(layer "F.SilkS")
		)
		(fp_rect
			(start -0.5842 1.3335)
			(end 0.5842 -1.3335)
			(stroke
				(width 0)
				(type default)
			)
			(fill no)
			(layer "F.CrtYd")
		)
		(fp_rect
			(start -0.5842 1.3335)
			(end 0.5842 -1.3335)
			(stroke
				(width 0)
				(type default)
			)
			(fill no)
			(layer "F.Fab")
		)
		(pad "1" smd custom
			(at 0 -0.762 270)
			(size 0.2159 0.2159)
			(layers "F.Cu" "F.Mask" "F.Paste")
			(net "FANIN_9")
			(options
				(clearance outline)
				(anchor circle)
			)
			(primitives
				(gr_poly
					(pts
						(arc
							(start -0.3302 -0.4318)
							(mid -0.402042 -0.402042)
							(end -0.4318 -0.3302)
						)
						(arc
							(start -0.4318 0.3302)
							(mid -0.402042 0.402042)
							(end -0.3302 0.4318)
						)
						(arc
							(start 0.3302 0.4318)
							(mid 0.402042 0.402042)
							(end 0.4318 0.3302)
						)
						(arc
							(start 0.4318 -0.3302)
							(mid 0.402042 -0.402042)
							(end 0.3302 -0.4318)
						)
					)
					(width 0)
					(fill yes)
				)
			)
		)
		(pad "2" smd custom
			(at 0 0.762 270)
			(size 0.2159 0.2159)
			(layers "F.Cu" "F.Mask" "F.Paste")
			(net "FAN_TACH9")
			(options
				(clearance outline)
				(anchor circle)
			)
			(primitives
				(gr_poly
					(pts
						(arc
							(start -0.3302 -0.4318)
							(mid -0.402042 -0.402042)
							(end -0.4318 -0.3302)
						)
						(arc
							(start -0.4318 0.3302)
							(mid -0.402042 0.402042)
							(end -0.3302 0.4318)
						)
						(arc
							(start 0.3302 0.4318)
							(mid 0.402042 0.402042)
							(end 0.4318 0.3302)
						)
						(arc
							(start 0.4318 -0.3302)
							(mid 0.402042 -0.402042)
							(end 0.3302 -0.4318)
						)
					)
					(width 0)
					(fill yes)
				)
			)
		)
	)
	(footprint ""
		(layer "F.Cu")
		(at 14.224 -157.353 180)
		(property "Reference" "R181"
			(at 0 0 180)
			(layer "F.SilkS")
			(hide yes)
			(effects
				(font
					(size 1.27 1.27)
				)
			)
		)
		(property "Value" "0R1206-PAD-1-GP"
			(at 0 -5.0292 180)
			(unlocked yes)
			(layer "F.Fab")
			(hide yes)
			(effects
				(font
					(size 1.016 1.016)
					(thickness 0.1524)
				)
			)
		)
		(property "Device Type" "0R1206-PAD-1"
			(at 0 -6.5532 180)
			(unlocked yes)
			(layer "F.Fab")
			(hide yes)
			(effects
				(font
					(size 1.016 1.016)
					(thickness 0.1524)
				)
			)
		)
		(duplicate_pad_numbers_are_jumpers no)
		(fp_line
			(start 1.016 2.2352)
			(end 1.016 -2.2352)
			(stroke
				(width 0.1524)
				(type default)
			)
			(layer "F.SilkS")
		)
		(fp_line
			(start 1.016 -2.2352)
			(end -1.016 -2.2352)
			(stroke
				(width 0.1524)
				(type default)
			)
			(layer "F.SilkS")
		)
		(fp_line
			(start -1.016 2.2352)
			(end 1.016 2.2352)
			(stroke
				(width 0.1524)
				(type default)
			)
			(layer "F.SilkS")
		)
		(fp_line
			(start -1.016 -2.2352)
			(end -1.016 2.2352)
			(stroke
				(width 0.1524)
				(type default)
			)
			(layer "F.SilkS")
		)
		(fp_rect
			(start -1.0922 2.3114)
			(end 1.0922 -2.3114)
			(stroke
				(width 0)
				(type default)
			)
			(fill no)
			(layer "F.CrtYd")
		)
		(fp_poly
			(pts
				(xy -1.0922 -2.3114) (xy 1.0922 -2.3114) (xy 1.0922 2.3114) (xy -1.0922 2.3114)
			)
			(stroke
				(width 0)
				(type default)
			)
			(fill no)
			(layer "F.Fab")
		)
		(pad "1" smd rect
			(at 0 -1.397 180)
			(size 1.651 2.0574)
			(drill
				(offset 0 0.3937)
			)
			(layers "F.Cu" "F.Mask" "F.Paste")
			(net "P12V_FAN5")
		)
		(pad "2" smd rect
			(at 0 1.397 180)
			(size 1.651 2.0574)
			(drill
				(offset 0 -0.3937)
			)
			(layers "F.Cu" "F.Mask" "F.Paste")
			(net "P12V")
		)
	)
)
